(kicad_pcb
	(version 20260206)
	(generator "pcbnew")
	(generator_version "10.0")
	(general
		(thickness 1.6)
		(legacy_teardrops no)
	)
	(paper "A4")
	(title_block
		(title "baseboard — 13948-1b.1110WZS1818.brd")
		(comment 1 "Honey Badger (Wiwynn) / footprints 2293-2299 of 2523")
	)
	(layers
		(0 "F.Cu" signal "TOP")
		(4 "In1.Cu" signal "L2GND")
		(6 "In2.Cu" signal "L3")
		(8 "In3.Cu" signal "L4VCC")
		(10 "In4.Cu" signal "L5VCC")
		(12 "In5.Cu" signal "L6")
		(14 "In6.Cu" signal "L7GND")
		(2 "B.Cu" signal "BOTTOM")
		(9 "F.Adhes" user "F.Adhesive")
		(11 "B.Adhes" user "B.Adhesive")
		(13 "F.Paste" user "Package Geometry/Pastemask Top")
		(15 "B.Paste" user "Package Geometry/Pastemask Bottom")
		(5 "F.SilkS" user "Ref Des/Silkscreen Top")
		(7 "B.SilkS" user "Ref Des/Silkscreen Bottom")
		(1 "F.Mask" user "Board Geometry/Soldermask Top")
		(3 "B.Mask" user "Board Geometry/Soldermask Bottom")
		(17 "Dwgs.User" user "User.Drawings")
		(19 "Cmts.User" user "User.Comments")
		(21 "Eco1.User" user "User.Eco1")
		(23 "Eco2.User" user "User.Eco2")
		(25 "Edge.Cuts" user "Board Geometry/Outline")
		(27 "Margin" user)
		(31 "F.CrtYd" user "Package Geometry/Place Bound Top")
		(29 "B.CrtYd" user "Package Geometry/Place Bound Bottom")
		(35 "F.Fab" user "Ref Des/Assembly Top")
		(33 "B.Fab" user "Ref Des/Assembly Bottom")
	)
	(footprint ""
		(layer "B.Cu")
		(at 172.339 -103.759)
		(property "Reference" "PR155"
			(at 0 0 0)
			(layer "B.SilkS")
			(hide yes)
			(effects
				(font
					(size 1.27 1.27)
				)
				(justify mirror)
			)
		)
		(property "Value" "2K21R2F-GP"
			(at -0.064008 -3.993896 0)
			(unlocked yes)
			(layer "B.Fab")
			(hide yes)
			(effects
				(font
					(size 1.016 1.016)
					(thickness 0.1524)
				)
				(justify mirror)
			)
		)
		(property "Device Type" "R402H16"
			(at -0.064008 -5.517896 0)
			(unlocked yes)
			(layer "B.Fab")
			(hide yes)
			(effects
				(font
					(size 1.016 1.016)
					(thickness 0.1524)
				)
				(justify mirror)
			)
		)
		(duplicate_pad_numbers_are_jumpers no)
		(fp_line
			(start -0.508 -0.9398)
			(end 0.508 -0.9398)
			(stroke
				(width 0.1524)
				(type default)
			)
			(layer "B.SilkS")
		)
		(fp_line
			(start 0.508 -0.9398)
			(end 0.508 0.9398)
			(stroke
				(width 0.1524)
				(type default)
			)
			(layer "B.SilkS")
		)
		(fp_rect
			(start 0.508 0.9398)
			(end -0.508 -0.9398)
			(stroke
				(width 0)
				(type default)
			)
			(fill no)
			(layer "B.CrtYd")
		)
		(fp_rect
			(start 0.508 0.9398)
			(end -0.508 -0.9398)
			(stroke
				(width 0)
				(type default)
			)
			(fill no)
			(layer "B.Fab")
		)
		(pad "1" smd custom
			(at 0 -0.4445 180)
			(size 0.1397 0.1397)
			(layers "B.Cu" "B.Mask" "B.Paste")
			(net "P0V9_E_LX")
			(options
				(clearance outline)
				(anchor circle)
			)
			(primitives
				(gr_poly
					(pts
						(arc
							(start -0.1778 0.2794)
							(mid -0.249642 0.249642)
							(end -0.2794 0.1778)
						)
						(arc
							(start -0.2794 -0.1778)
							(mid -0.249642 -0.249642)
							(end -0.1778 -0.2794)
						)
						(arc
							(start 0.1778 -0.2794)
							(mid 0.249642 -0.249642)
							(end 0.2794 -0.1778)
						)
						(arc
							(start 0.2794 0.1778)
							(mid 0.249642 0.249642)
							(end 0.1778 0.2794)
						)
					)
					(width 0)
					(fill yes)
				)
			)
		)
		(pad "2" smd custom
			(at 0 0.4445 180)
			(size 0.1397 0.1397)
			(layers "B.Cu" "B.Mask" "B.Paste")
			(net "P0V9_E_SW_R")
			(options
				(clearance outline)
				(anchor circle)
			)
			(primitives
				(gr_poly
					(pts
						(arc
							(start -0.1778 0.2794)
							(mid -0.249642 0.249642)
							(end -0.2794 0.1778)
						)
						(arc
							(start -0.2794 -0.1778)
							(mid -0.249642 -0.249642)
							(end -0.1778 -0.2794)
						)
						(arc
							(start 0.1778 -0.2794)
							(mid 0.249642 -0.249642)
							(end 0.2794 -0.1778)
						)
						(arc
							(start 0.2794 0.1778)
							(mid 0.249642 0.249642)
							(end 0.1778 0.2794)
						)
					)
					(width 0)
					(fill yes)
				)
			)
		)
	)
	(footprint ""
		(layer "B.Cu")
		(at 108.020612 -211.582 -90)
		(property "Reference" "SR907"
			(at 0 0 90)
			(layer "B.SilkS")
			(hide yes)
			(effects
				(font
					(size 1.27 1.27)
				)
				(justify mirror)
			)
		)
		(property "Value" "4K7R2F-GP"
			(at -0.064008 -3.993896 270)
			(unlocked yes)
			(layer "B.Fab")
			(hide yes)
			(effects
				(font
					(size 1.016 1.016)
					(thickness 0.1524)
				)
				(justify mirror)
			)
		)
		(property "Device Type" "R402H16"
			(at -0.064008 -5.517896 270)
			(unlocked yes)
			(layer "B.Fab")
			(hide yes)
			(effects
				(font
					(size 1.016 1.016)
					(thickness 0.1524)
				)
				(justify mirror)
			)
		)
		(duplicate_pad_numbers_are_jumpers no)
		(fp_line
			(start -0.508 -0.9398)
			(end 0.508 -0.9398)
			(stroke
				(width 0.1524)
				(type default)
			)
			(layer "B.SilkS")
		)
		(fp_line
			(start 0.508 -0.9398)
			(end 0.508 0.9398)
			(stroke
				(width 0.1524)
				(type default)
			)
			(layer "B.SilkS")
		)
		(fp_rect
			(start 0.508 0.9398)
			(end -0.508 -0.9398)
			(stroke
				(width 0)
				(type default)
			)
			(fill no)
			(layer "B.CrtYd")
		)
		(fp_rect
			(start 0.508 0.9398)
			(end -0.508 -0.9398)
			(stroke
				(width 0)
				(type default)
			)
			(fill no)
			(layer "B.Fab")
		)
		(pad "1" smd custom
			(at 0 -0.4445 90)
			(size 0.1397 0.1397)
			(layers "B.Cu" "B.Mask" "B.Paste")
			(net "REDV_D2_B")
			(options
				(clearance outline)
				(anchor circle)
			)
			(primitives
				(gr_poly
					(pts
						(arc
							(start -0.1778 0.2794)
							(mid -0.249642 0.249642)
							(end -0.2794 0.1778)
						)
						(arc
							(start -0.2794 -0.1778)
							(mid -0.249642 -0.249642)
							(end -0.1778 -0.2794)
						)
						(arc
							(start 0.1778 -0.2794)
							(mid 0.249642 -0.249642)
							(end 0.2794 -0.1778)
						)
						(arc
							(start 0.2794 0.1778)
							(mid 0.249642 0.249642)
							(end 0.1778 0.2794)
						)
					)
					(width 0)
					(fill yes)
				)
			)
		)
		(pad "2" smd custom
			(at 0 0.4445 90)
			(size 0.1397 0.1397)
			(layers "B.Cu" "B.Mask" "B.Paste")
			(net "GND")
			(options
				(clearance outline)
				(anchor circle)
			)
			(primitives
				(gr_poly
					(pts
						(arc
							(start -0.1778 0.2794)
							(mid -0.249642 0.249642)
							(end -0.2794 0.1778)
						)
						(arc
							(start -0.2794 -0.1778)
							(mid -0.249642 -0.249642)
							(end -0.1778 -0.2794)
						)
						(arc
							(start 0.1778 -0.2794)
							(mid 0.249642 -0.249642)
							(end 0.2794 -0.1778)
						)
						(arc
							(start 0.2794 0.1778)
							(mid 0.249642 0.249642)
							(end 0.1778 0.2794)
						)
					)
					(width 0)
					(fill yes)
				)
			)
		)
	)
	(footprint ""
		(layer "B.Cu")
		(at 290.4744 -173.9392 90)
		(property "Reference" "C209"
			(at 0 0 90)
			(layer "B.SilkS")
			(hide yes)
			(effects
				(font
					(size 1.27 1.27)
				)
				(justify mirror)
			)
		)
		(property "Value" "SC220P50V2KX-3GP"
			(at -1.1811 -2.7051 90)
			(unlocked yes)
			(layer "B.Fab")
			(hide yes)
			(effects
				(font
					(size 1.016 1.016)
					(thickness 0.1524)
				)
				(justify mirror)
			)
		)
		(property "Device Type" "C402H22"
			(at -1.1811 -4.2291 90)
			(unlocked yes)
			(layer "B.Fab")
			(hide yes)
			(effects
				(font
					(size 1.016 1.016)
					(thickness 0.1524)
				)
				(justify mirror)
			)
		)
		(duplicate_pad_numbers_are_jumpers no)
		(fp_rect
			(start 0.4318 0.9525)
			(end -0.4318 -0.9525)
			(stroke
				(width 0)
				(type default)
			)
			(fill no)
			(layer "B.CrtYd")
		)
		(fp_rect
			(start 0.4318 0.9525)
			(end -0.4318 -0.9525)
			(stroke
				(width 0)
				(type default)
			)
			(fill no)
			(layer "B.Fab")
		)
		(pad "1" smd custom
			(at 0 -0.4445 270)
			(size 0.1524 0.1524)
			(layers "B.Cu" "B.Mask" "B.Paste")
			(net "P3V3_STBY")
			(options
				(clearance outline)
				(anchor circle)
			)
			(primitives
				(gr_poly
					(pts
						(arc
							(start 0.3048 0.2032)
							(mid 0.275042 0.275042)
							(end 0.2032 0.3048)
						)
						(arc
							(start -0.2032 0.3048)
							(mid -0.275042 0.275042)
							(end -0.3048 0.2032)
						)
						(arc
							(start -0.3048 -0.2032)
							(mid -0.275042 -0.275042)
							(end -0.2032 -0.3048)
						)
						(arc
							(start 0.2032 -0.3048)
							(mid 0.275042 -0.275042)
							(end 0.3048 -0.2032)
						)
					)
					(width 0)
					(fill yes)
				)
			)
		)
		(pad "2" smd custom
			(at 0 0.4445 270)
			(size 0.1524 0.1524)
			(layers "B.Cu" "B.Mask" "B.Paste")
			(net "GND")
			(options
				(clearance outline)
				(anchor circle)
			)
			(primitives
				(gr_poly
					(pts
						(arc
							(start 0.3048 0.2032)
							(mid 0.275042 0.275042)
							(end 0.2032 0.3048)
						)
						(arc
							(start -0.2032 0.3048)
							(mid -0.275042 0.275042)
							(end -0.3048 0.2032)
						)
						(arc
							(start -0.3048 -0.2032)
							(mid -0.275042 -0.275042)
							(end -0.2032 -0.3048)
						)
						(arc
							(start 0.2032 -0.3048)
							(mid 0.275042 -0.275042)
							(end 0.3048 -0.2032)
						)
					)
					(width 0)
					(fill yes)
				)
			)
		)
	)
	(footprint ""
		(layer "B.Cu")
		(at 107.169966 -43.307 90)
		(property "Reference" "SC1026"
			(at 0 0 90)
			(layer "B.SilkS")
			(hide yes)
			(effects
				(font
					(size 1.27 1.27)
				)
				(justify mirror)
			)
		)
		(property "Value" "SC1U10V2KX-4-GP"
			(at -1.1811 -2.7051 90)
			(unlocked yes)
			(layer "B.Fab")
			(hide yes)
			(effects
				(font
					(size 1.016 1.016)
					(thickness 0.1524)
				)
				(justify mirror)
			)
		)
		(property "Device Type" "C402H22"
			(at -1.1811 -4.2291 90)
			(unlocked yes)
			(layer "B.Fab")
			(hide yes)
			(effects
				(font
					(size 1.016 1.016)
					(thickness 0.1524)
				)
				(justify mirror)
			)
		)
		(duplicate_pad_numbers_are_jumpers no)
		(fp_rect
			(start 0.4318 0.9525)
			(end -0.4318 -0.9525)
			(stroke
				(width 0)
				(type default)
			)
			(fill no)
			(layer "B.CrtYd")
		)
		(fp_rect
			(start 0.4318 0.9525)
			(end -0.4318 -0.9525)
			(stroke
				(width 0)
				(type default)
			)
			(fill no)
			(layer "B.Fab")
		)
		(pad "1" smd custom
			(at 0 -0.4445 270)
			(size 0.1524 0.1524)
			(layers "B.Cu" "B.Mask" "B.Paste")
			(net "P0V955_C")
			(options
				(clearance outline)
				(anchor circle)
			)
			(primitives
				(gr_poly
					(pts
						(arc
							(start 0.3048 0.2032)
							(mid 0.275042 0.275042)
							(end 0.2032 0.3048)
						)
						(arc
							(start -0.2032 0.3048)
							(mid -0.275042 0.275042)
							(end -0.3048 0.2032)
						)
						(arc
							(start -0.3048 -0.2032)
							(mid -0.275042 -0.275042)
							(end -0.2032 -0.3048)
						)
						(arc
							(start 0.2032 -0.3048)
							(mid 0.275042 -0.275042)
							(end 0.3048 -0.2032)
						)
					)
					(width 0)
					(fill yes)
				)
			)
		)
		(pad "2" smd custom
			(at 0 0.4445 270)
			(size 0.1524 0.1524)
			(layers "B.Cu" "B.Mask" "B.Paste")
			(net "GND")
			(options
				(clearance outline)
				(anchor circle)
			)
			(primitives
				(gr_poly
					(pts
						(arc
							(start 0.3048 0.2032)
							(mid 0.275042 0.275042)
							(end 0.2032 0.3048)
						)
						(arc
							(start -0.2032 0.3048)
							(mid -0.275042 0.275042)
							(end -0.3048 0.2032)
						)
						(arc
							(start -0.3048 -0.2032)
							(mid -0.275042 -0.275042)
							(end -0.2032 -0.3048)
						)
						(arc
							(start 0.2032 -0.3048)
							(mid 0.275042 -0.275042)
							(end 0.3048 -0.2032)
						)
					)
					(width 0)
					(fill yes)
				)
			)
		)
	)
	(footprint ""
		(layer "B.Cu")
		(at 29.414216 -232.33888)
		(property "Reference" "R506"
			(at 0 0 0)
			(layer "B.SilkS")
			(hide yes)
			(effects
				(font
					(size 1.27 1.27)
				)
				(justify mirror)
			)
		)
		(property "Value" "0R2J-2-GP"
			(at -0.064008 -3.993896 0)
			(unlocked yes)
			(layer "B.Fab")
			(hide yes)
			(effects
				(font
					(size 1.016 1.016)
					(thickness 0.1524)
				)
				(justify mirror)
			)
		)
		(property "Device Type" "R402H16"
			(at -0.064008 -5.517896 0)
			(unlocked yes)
			(layer "B.Fab")
			(hide yes)
			(effects
				(font
					(size 1.016 1.016)
					(thickness 0.1524)
				)
				(justify mirror)
			)
		)
		(duplicate_pad_numbers_are_jumpers no)
		(fp_line
			(start -0.508 -0.9398)
			(end 0.508 -0.9398)
			(stroke
				(width 0.1524)
				(type default)
			)
			(layer "B.SilkS")
		)
		(fp_line
			(start 0.508 -0.9398)
			(end 0.508 0.9398)
			(stroke
				(width 0.1524)
				(type default)
			)
			(layer "B.SilkS")
		)
		(fp_rect
			(start 0.508 0.9398)
			(end -0.508 -0.9398)
			(stroke
				(width 0)
				(type default)
			)
			(fill no)
			(layer "B.CrtYd")
		)
		(fp_rect
			(start 0.508 0.9398)
			(end -0.508 -0.9398)
			(stroke
				(width 0)
				(type default)
			)
			(fill no)
			(layer "B.Fab")
		)
		(pad "1" smd custom
			(at 0 -0.4445 180)
			(size 0.1397 0.1397)
			(layers "B.Cu" "B.Mask" "B.Paste")
			(net "SAS_HDD_PWR4_PCIE")
			(options
				(clearance outline)
				(anchor circle)
			)
			(primitives
				(gr_poly
					(pts
						(arc
							(start -0.1778 0.2794)
							(mid -0.249642 0.249642)
							(end -0.2794 0.1778)
						)
						(arc
							(start -0.2794 -0.1778)
							(mid -0.249642 -0.249642)
							(end -0.1778 -0.2794)
						)
						(arc
							(start 0.1778 -0.2794)
							(mid 0.249642 -0.249642)
							(end 0.2794 -0.1778)
						)
						(arc
							(start 0.2794 0.1778)
							(mid 0.249642 0.249642)
							(end 0.1778 0.2794)
						)
					)
					(width 0)
					(fill yes)
				)
			)
		)
		(pad "2" smd custom
			(at 0 0.4445 180)
			(size 0.1397 0.1397)
			(layers "B.Cu" "B.Mask" "B.Paste")
			(net "SAS_HDD_PWR4")
			(options
				(clearance outline)
				(anchor circle)
			)
			(primitives
				(gr_poly
					(pts
						(arc
							(start -0.1778 0.2794)
							(mid -0.249642 0.249642)
							(end -0.2794 0.1778)
						)
						(arc
							(start -0.2794 -0.1778)
							(mid -0.249642 -0.249642)
							(end -0.1778 -0.2794)
						)
						(arc
							(start 0.1778 -0.2794)
							(mid 0.249642 -0.249642)
							(end 0.2794 -0.1778)
						)
						(arc
							(start 0.2794 0.1778)
							(mid 0.249642 0.249642)
							(end 0.1778 0.2794)
						)
					)
					(width 0)
					(fill yes)
				)
			)
		)
	)
	(footprint ""
		(layer "B.Cu")
		(at 108.458 -79.883 -90)
		(property "Reference" "SR773"
			(at 0 0 90)
			(layer "B.SilkS")
			(hide yes)
			(effects
				(font
					(size 1.27 1.27)
				)
				(justify mirror)
			)
		)
		(property "Value" "4K75R2F-1-GP"
			(at -0.064008 -3.993896 270)
			(unlocked yes)
			(layer "B.Fab")
			(hide yes)
			(effects
				(font
					(size 1.016 1.016)
					(thickness 0.1524)
				)
				(justify mirror)
			)
		)
		(property "Device Type" "R402H16"
			(at -0.064008 -5.517896 270)
			(unlocked yes)
			(layer "B.Fab")
			(hide yes)
			(effects
				(font
					(size 1.016 1.016)
					(thickness 0.1524)
				)
				(justify mirror)
			)
		)
		(duplicate_pad_numbers_are_jumpers no)
		(fp_line
			(start -0.508 -0.9398)
			(end 0.508 -0.9398)
			(stroke
				(width 0.1524)
				(type default)
			)
			(layer "B.SilkS")
		)
		(fp_line
			(start 0.508 -0.9398)
			(end 0.508 0.9398)
			(stroke
				(width 0.1524)
				(type default)
			)
			(layer "B.SilkS")
		)
		(fp_rect
			(start 0.508 0.9398)
			(end -0.508 -0.9398)
			(stroke
				(width 0)
				(type default)
			)
			(fill no)
			(layer "B.CrtYd")
		)
		(fp_rect
			(start 0.508 0.9398)
			(end -0.508 -0.9398)
			(stroke
				(width 0)
				(type default)
			)
			(fill no)
			(layer "B.Fab")
		)
		(pad "1" smd custom
			(at 0 -0.4445 90)
			(size 0.1397 0.1397)
			(layers "B.Cu" "B.Mask" "B.Paste")
			(net "P1V8_E")
			(options
				(clearance outline)
				(anchor circle)
			)
			(primitives
				(gr_poly
					(pts
						(arc
							(start -0.1778 0.2794)
							(mid -0.249642 0.249642)
							(end -0.2794 0.1778)
						)
						(arc
							(start -0.2794 -0.1778)
							(mid -0.249642 -0.249642)
							(end -0.1778 -0.2794)
						)
						(arc
							(start 0.1778 -0.2794)
							(mid 0.249642 -0.249642)
							(end 0.2794 -0.1778)
						)
						(arc
							(start 0.2794 0.1778)
							(mid 0.249642 0.249642)
							(end 0.1778 0.2794)
						)
					)
					(width 0)
					(fill yes)
				)
			)
		)
		(pad "2" smd custom
			(at 0 0.4445 90)
			(size 0.1397 0.1397)
			(layers "B.Cu" "B.Mask" "B.Paste")
			(net "SXP_ACTIVE_2")
			(options
				(clearance outline)
				(anchor circle)
			)
			(primitives
				(gr_poly
					(pts
						(arc
							(start -0.1778 0.2794)
							(mid -0.249642 0.249642)
							(end -0.2794 0.1778)
						)
						(arc
							(start -0.2794 -0.1778)
							(mid -0.249642 -0.249642)
							(end -0.1778 -0.2794)
						)
						(arc
							(start 0.1778 -0.2794)
							(mid 0.249642 -0.249642)
							(end 0.2794 -0.1778)
						)
						(arc
							(start 0.2794 0.1778)
							(mid 0.249642 0.249642)
							(end 0.1778 0.2794)
						)
					)
					(width 0)
					(fill yes)
				)
			)
		)
	)
	(footprint ""
		(layer "B.Cu")
		(at 101.454966 -46.609 -90)
		(property "Reference" "SC1034"
			(at 0 0 90)
			(layer "B.SilkS")
			(hide yes)
			(effects
				(font
					(size 1.27 1.27)
				)
				(justify mirror)
			)
		)
		(property "Value" "SC1KP50V2KX-1GP"
			(at -1.1811 -2.7051 270)
			(unlocked yes)
			(layer "B.Fab")
			(hide yes)
			(effects
				(font
					(size 1.016 1.016)
					(thickness 0.1524)
				)
				(justify mirror)
			)
		)
		(property "Device Type" "C402H22"
			(at -1.1811 -4.2291 270)
			(unlocked yes)
			(layer "B.Fab")
			(hide yes)
			(effects
				(font
					(size 1.016 1.016)
					(thickness 0.1524)
				)
				(justify mirror)
			)
		)
		(duplicate_pad_numbers_are_jumpers no)
		(fp_rect
			(start 0.4318 0.9525)
			(end -0.4318 -0.9525)
			(stroke
				(width 0)
				(type default)
			)
			(fill no)
			(layer "B.CrtYd")
		)
		(fp_rect
			(start 0.4318 0.9525)
			(end -0.4318 -0.9525)
			(stroke
				(width 0)
				(type default)
			)
			(fill no)
			(layer "B.Fab")
		)
		(pad "1" smd custom
			(at 0 -0.4445 90)
			(size 0.1524 0.1524)
			(layers "B.Cu" "B.Mask" "B.Paste")
			(net "P0V955_C")
			(options
				(clearance outline)
				(anchor circle)
			)
			(primitives
				(gr_poly
					(pts
						(arc
							(start 0.3048 0.2032)
							(mid 0.275042 0.275042)
							(end 0.2032 0.3048)
						)
						(arc
							(start -0.2032 0.3048)
							(mid -0.275042 0.275042)
							(end -0.3048 0.2032)
						)
						(arc
							(start -0.3048 -0.2032)
							(mid -0.275042 -0.275042)
							(end -0.2032 -0.3048)
						)
						(arc
							(start 0.2032 -0.3048)
							(mid 0.275042 -0.275042)
							(end 0.3048 -0.2032)
						)
					)
					(width 0)
					(fill yes)
				)
			)
		)
		(pad "2" smd custom
			(at 0 0.4445 90)
			(size 0.1524 0.1524)
			(layers "B.Cu" "B.Mask" "B.Paste")
			(net "GND")
			(options
				(clearance outline)
				(anchor circle)
			)
			(primitives
				(gr_poly
					(pts
						(arc
							(start 0.3048 0.2032)
							(mid 0.275042 0.275042)
							(end 0.2032 0.3048)
						)
						(arc
							(start -0.2032 0.3048)
							(mid -0.275042 0.275042)
							(end -0.3048 0.2032)
						)
						(arc
							(start -0.3048 -0.2032)
							(mid -0.275042 -0.275042)
							(end -0.2032 -0.3048)
						)
						(arc
							(start 0.2032 -0.3048)
							(mid 0.275042 -0.275042)
							(end 0.3048 -0.2032)
						)
					)
					(width 0)
					(fill yes)
				)
			)
		)
	)
)
